# S9S_MB_2U (Grand Teton) — schematic netlist excerpt (pin names and nets, part order shuffled) for the footprints in the layout excerpt that follows; sources: Cadence DE-HDL packaged netlist, KiCad conversion of 03242023_DA0F0TMBIJ0_F0T_Motherboard_J_brd_V01_OCP.brd

R3039  Q_RES  1K 1% CHIP  pkg 0402LF  page 201 : A = GND ; B = PD_ME_RCVR_N
C1824  Q_CAP  0.1UF 25V 10% X7R  pkg 0402  page 161 : A = P3V3_AUX ; B = GND
H96  HOLE  EMPTY  pkg TH  page 311 : \1\ = GND

(kicad_pcb
	(version 20260206)
	(generator "pcbnew")
	(generator_version "10.0")
	(general
		(thickness 1.6)
		(legacy_teardrops no)
	)
	(paper "A4")
	(title_block
		(title "03242023_DA0F0TMBIJ0_F0T_Motherboard_J_brd_V01_OCP.brd")
		(comment 1 "Grand Teton / footprints 3098-3100 of 6105")
	)
	(layers
		(0 "F.Cu" signal "TOP")
		(4 "In1.Cu" signal "GND")
		(6 "In2.Cu" signal "IN1")
		(8 "In3.Cu" signal "GND1")
		(10 "In4.Cu" signal "IN2")
		(12 "In5.Cu" signal "GND2")
		(14 "In6.Cu" signal "IN3")
		(16 "In7.Cu" signal "GND3")
		(18 "In8.Cu" signal "VCC")
		(20 "In9.Cu" signal "VCC1")
		(22 "In10.Cu" signal "GND4")
		(24 "In11.Cu" signal "IN4")
		(26 "In12.Cu" signal "GND5")
		(28 "In13.Cu" signal "IN5")
		(30 "In14.Cu" signal "GND6")
		(32 "In15.Cu" signal "IN6")
		(34 "In16.Cu" signal "GND7")
		(2 "B.Cu" signal "BOTTOM")
		(9 "F.Adhes" user "F.Adhesive")
		(11 "B.Adhes" user "B.Adhesive")
		(13 "F.Paste" user "Package Geometry/Pastemask Top")
		(15 "B.Paste" user "Package Geometry/Pastemask Bottom")
		(5 "F.SilkS" user "Ref Des/Silkscreen Top")
		(7 "B.SilkS" user "Ref Des/Silkscreen Bottom")
		(1 "F.Mask" user "Board Geometry/Soldermask Top")
		(3 "B.Mask" user "Board Geometry/Soldermask Bottom")
		(17 "Dwgs.User" user "User.Drawings")
		(19 "Cmts.User" user "User.Comments")
		(21 "Eco1.User" user "User.Eco1")
		(23 "Eco2.User" user "User.Eco2")
		(25 "Edge.Cuts" user "Board Geometry/Outline")
		(27 "Margin" user)
		(31 "F.CrtYd" user "Package Geometry/Place Bound Top")
		(29 "B.CrtYd" user "Package Geometry/Place Bound Bottom")
		(35 "F.Fab" user "Ref Des/Assembly Top")
		(33 "B.Fab" user "Ref Des/Assembly Bottom")
	)
	(footprint ""
		(layer "F.Cu")
		(at 278.439626 -16.576548)
		(property "Reference" "C1824"
			(at 0 0 0)
			(layer "F.SilkS")
			(hide yes)
			(effects
				(font
					(size 1.27 1.27)
				)
			)
		)
		(property "Value" ""
			(at 0 0 0)
			(layer "F.Fab")
			(effects
				(font
					(size 1.27 1.27)
				)
			)
		)
		(duplicate_pad_numbers_are_jumpers no)
		(fp_line
			(start -0.7874 -0.4064)
			(end 0.7874 -0.4064)
			(stroke
				(width 0.1524)
				(type default)
			)
			(layer "F.SilkS")
		)
		(fp_line
			(start -0.7874 0.4064)
			(end -0.7874 -0.4064)
			(stroke
				(width 0.1524)
				(type default)
			)
			(layer "F.SilkS")
		)
		(fp_line
			(start 0.7874 -0.4064)
			(end 0.7874 0.4064)
			(stroke
				(width 0.1524)
				(type default)
			)
			(layer "F.SilkS")
		)
		(fp_line
			(start 0.7874 0.4064)
			(end -0.7874 0.4064)
			(stroke
				(width 0.1524)
				(type default)
			)
			(layer "F.SilkS")
		)
		(fp_line
			(start -0.67945 -0.305054)
			(end -0.12065 -0.305054)
			(stroke
				(width 0.1)
				(type default)
			)
			(layer "F.Fab")
		)
		(fp_line
			(start -0.67945 0.3048)
			(end -0.67945 -0.305054)
			(stroke
				(width 0.1)
				(type default)
			)
			(layer "F.Fab")
		)
		(fp_line
			(start -0.12065 -0.305054)
			(end -0.12065 -0.2794)
			(stroke
				(width 0.1)
				(type default)
			)
			(layer "F.Fab")
		)
		(fp_line
			(start -0.12065 -0.2794)
			(end 0.12065 -0.2794)
			(stroke
				(width 0.1)
				(type default)
			)
			(layer "F.Fab")
		)
		(fp_line
			(start -0.12065 0.2794)
			(end -0.12065 0.3048)
			(stroke
				(width 0.1)
				(type default)
			)
			(layer "F.Fab")
		)
		(fp_line
			(start -0.12065 0.3048)
			(end -0.67945 0.3048)
			(stroke
				(width 0.1)
				(type default)
			)
			(layer "F.Fab")
		)
		(fp_line
			(start 0.120396 0.2794)
			(end -0.12065 0.2794)
			(stroke
				(width 0.1)
				(type default)
			)
			(layer "F.Fab")
		)
		(fp_line
			(start 0.120396 0.3048)
			(end 0.120396 0.2794)
			(stroke
				(width 0.1)
				(type default)
			)
			(layer "F.Fab")
		)
		(fp_line
			(start 0.12065 -0.3048)
			(end 0.67945 -0.3048)
			(stroke
				(width 0.1)
				(type default)
			)
			(layer "F.Fab")
		)
		(fp_line
			(start 0.12065 -0.2794)
			(end 0.12065 -0.3048)
			(stroke
				(width 0.1)
				(type default)
			)
			(layer "F.Fab")
		)
		(fp_line
			(start 0.67945 -0.3048)
			(end 0.67945 0.3048)
			(stroke
				(width 0.1)
				(type default)
			)
			(layer "F.Fab")
		)
		(fp_line
			(start 0.67945 0.3048)
			(end 0.120396 0.3048)
			(stroke
				(width 0.1)
				(type default)
			)
			(layer "F.Fab")
		)
		(pad "1" smd circle
			(at -0.40005 0)
			(size 0 0)
			(layers "F.Cu" "F.Mask" "F.Paste")
			(net "P3V3_AUX")
		)
		(pad "2" smd circle
			(at 0.40005 0)
			(size 0 0)
			(layers "F.Cu" "F.Mask" "F.Paste")
			(net "GND")
		)
	)
	(footprint ""
		(layer "F.Cu")
		(at 413.520382 -30.893258)
		(property "Reference" "R3039"
			(at 0 0 0)
			(layer "F.SilkS")
			(hide yes)
			(effects
				(font
					(size 1.27 1.27)
				)
			)
		)
		(property "Value" ""
			(at 0 0 0)
			(layer "F.Fab")
			(effects
				(font
					(size 1.27 1.27)
				)
			)
		)
		(duplicate_pad_numbers_are_jumpers no)
		(fp_line
			(start -0.7874 -0.4064)
			(end 0.7874 -0.4064)
			(stroke
				(width 0.1524)
				(type default)
			)
			(layer "F.SilkS")
		)
		(fp_line
			(start -0.7874 0.4064)
			(end -0.7874 -0.4064)
			(stroke
				(width 0.1524)
				(type default)
			)
			(layer "F.SilkS")
		)
		(fp_line
			(start 0.7874 -0.4064)
			(end 0.7874 0.4064)
			(stroke
				(width 0.1524)
				(type default)
			)
			(layer "F.SilkS")
		)
		(fp_line
			(start 0.7874 0.4064)
			(end -0.7874 0.4064)
			(stroke
				(width 0.1524)
				(type default)
			)
			(layer "F.SilkS")
		)
		(fp_line
			(start -0.67945 -0.305054)
			(end -0.12065 -0.305054)
			(stroke
				(width 0.1)
				(type default)
			)
			(layer "F.Fab")
		)
		(fp_line
			(start -0.67945 0.3048)
			(end -0.67945 -0.305054)
			(stroke
				(width 0.1)
				(type default)
			)
			(layer "F.Fab")
		)
		(fp_line
			(start -0.12065 -0.305054)
			(end -0.12065 -0.2794)
			(stroke
				(width 0.1)
				(type default)
			)
			(layer "F.Fab")
		)
		(fp_line
			(start -0.12065 -0.2794)
			(end 0.12065 -0.2794)
			(stroke
				(width 0.1)
				(type default)
			)
			(layer "F.Fab")
		)
		(fp_line
			(start -0.12065 0.2794)
			(end -0.12065 0.3048)
			(stroke
				(width 0.1)
				(type default)
			)
			(layer "F.Fab")
		)
		(fp_line
			(start -0.12065 0.3048)
			(end -0.67945 0.3048)
			(stroke
				(width 0.1)
				(type default)
			)
			(layer "F.Fab")
		)
		(fp_line
			(start 0.120396 0.2794)
			(end -0.12065 0.2794)
			(stroke
				(width 0.1)
				(type default)
			)
			(layer "F.Fab")
		)
		(fp_line
			(start 0.120396 0.3048)
			(end 0.120396 0.2794)
			(stroke
				(width 0.1)
				(type default)
			)
			(layer "F.Fab")
		)
		(fp_line
			(start 0.12065 -0.3048)
			(end 0.67945 -0.3048)
			(stroke
				(width 0.1)
				(type default)
			)
			(layer "F.Fab")
		)
		(fp_line
			(start 0.12065 -0.2794)
			(end 0.12065 -0.3048)
			(stroke
				(width 0.1)
				(type default)
			)
			(layer "F.Fab")
		)
		(fp_line
			(start 0.67945 -0.3048)
			(end 0.67945 0.3048)
			(stroke
				(width 0.1)
				(type default)
			)
			(layer "F.Fab")
		)
		(fp_line
			(start 0.67945 0.3048)
			(end 0.120396 0.3048)
			(stroke
				(width 0.1)
				(type default)
			)
			(layer "F.Fab")
		)
		(pad "1" smd circle
			(at -0.40005 0)
			(size 0 0)
			(layers "F.Cu" "F.Mask" "F.Paste")
			(net "GND")
		)
		(pad "2" smd circle
			(at 0.40005 0)
			(size 0 0)
			(layers "F.Cu" "F.Mask" "F.Paste")
			(net "PD_ME_RCVR_N")
		)
	)
	(footprint ""
		(layer "F.Cu")
		(at 12.999974 -435.600094)
		(property "Reference" "H96"
			(at -5.463794 -5.055616 0)
			(unlocked yes)
			(layer "F.SilkS")
			(effects
				(font
					(size 0.7874 0.5842)
					(thickness 0.1524)
				)
				(justify left)
			)
		)
		(property "Value" ""
			(at 0 0 0)
			(layer "F.Fab")
			(effects
				(font
					(size 1.27 1.27)
				)
			)
		)
		(duplicate_pad_numbers_are_jumpers no)
		(pad "1" thru_hole circle
			(at 0 0)
			(size 10.0076 10.0076)
			(drill 5.6134)
			(layers "*.Cu" "*.Mask")
			(remove_unused_layers no)
			(net "GND")
			(clearance -1.9431)
		)
	)
)
